# T6G (Grand Teton) — schematic netlist excerpt (pin names and nets, part order shuffled) for the footprints in the layout excerpt that follows; sources: Cadence DE-HDL packaged netlist, KiCad conversion of 04192023_DAF0TMB3IC0_F0TG_MB_C_brd_V02_OCP.brd

C6116  Q_CAP  0.01UF 50V 10% X7R  pkg C0402  page 179 : A = P1V2_CPU0_USB2_DVDD12 ; B = GND
R384  Q_RES  15 1% CHIP  pkg 0402LF  page 19 : A = M_J_CPU0_ALERT_N ; B = M_J_CPU0_ALERT_R_N

(kicad_pcb
	(version 20260206)
	(generator "pcbnew")
	(generator_version "10.0")
	(general
		(thickness 1.6)
		(legacy_teardrops no)
	)
	(paper "A4")
	(title_block
		(title "04192023_DAF0TMB3IC0_F0TG_MB_C_brd_V02_OCP.brd")
		(comment 1 "Grand Teton / footprints 6858-6859 of 8354")
	)
	(layers
		(0 "F.Cu" signal "TOP")
		(4 "In1.Cu" signal "GND")
		(6 "In2.Cu" signal "IN1")
		(8 "In3.Cu" signal "GND1")
		(10 "In4.Cu" signal "IN2")
		(12 "In5.Cu" signal "GND2")
		(14 "In6.Cu" signal "IN3")
		(16 "In7.Cu" signal "GND3")
		(18 "In8.Cu" signal "VCC")
		(20 "In9.Cu" signal "VCC1")
		(22 "In10.Cu" signal "GND4")
		(24 "In11.Cu" signal "IN4")
		(26 "In12.Cu" signal "GND5")
		(28 "In13.Cu" signal "IN5")
		(30 "In14.Cu" signal "GND6")
		(32 "In15.Cu" signal "IN6")
		(34 "In16.Cu" signal "GND7")
		(2 "B.Cu" signal "BOTTOM")
		(9 "F.Adhes" user "F.Adhesive")
		(11 "B.Adhes" user "B.Adhesive")
		(13 "F.Paste" user "Package Geometry/Pastemask Top")
		(15 "B.Paste" user "Package Geometry/Pastemask Bottom")
		(5 "F.SilkS" user "Ref Des/Silkscreen Top")
		(7 "B.SilkS" user "Ref Des/Silkscreen Bottom")
		(1 "F.Mask" user "Board Geometry/Soldermask Top")
		(3 "B.Mask" user "Board Geometry/Soldermask Bottom")
		(17 "Dwgs.User" user "User.Drawings")
		(19 "Cmts.User" user "User.Comments")
		(21 "Eco1.User" user "User.Eco1")
		(23 "Eco2.User" user "User.Eco2")
		(25 "Edge.Cuts" user "Board Geometry/Outline")
		(27 "Margin" user)
		(31 "F.CrtYd" user "Package Geometry/Place Bound Top")
		(29 "B.CrtYd" user "Package Geometry/Place Bound Bottom")
		(35 "F.Fab" user "Ref Des/Assembly Top")
		(33 "B.Fab" user "Ref Des/Assembly Bottom")
	)
	(footprint ""
		(layer "B.Cu")
		(at 438.103264 -244.08511)
		(property "Reference" "R384"
			(at 0 0 0)
			(layer "B.SilkS")
			(hide yes)
			(effects
				(font
					(size 1.27 1.27)
				)
				(justify mirror)
			)
		)
		(property "Value" ""
			(at 0 0 0)
			(layer "B.Fab")
			(effects
				(font
					(size 1.27 1.27)
				)
				(justify mirror)
			)
		)
		(duplicate_pad_numbers_are_jumpers no)
		(fp_line
			(start -0.7874 -0.4064)
			(end -0.7874 0.4064)
			(stroke
				(width 0.1524)
				(type default)
			)
			(layer "B.SilkS")
		)
		(fp_line
			(start -0.7874 0.4064)
			(end 0.7874 0.4064)
			(stroke
				(width 0.1524)
				(type default)
			)
			(layer "B.SilkS")
		)
		(fp_line
			(start 0.7874 -0.4064)
			(end -0.7874 -0.4064)
			(stroke
				(width 0.1524)
				(type default)
			)
			(layer "B.SilkS")
		)
		(fp_line
			(start 0.7874 0.4064)
			(end 0.7874 -0.4064)
			(stroke
				(width 0.1524)
				(type default)
			)
			(layer "B.SilkS")
		)
		(fp_line
			(start -0.67945 -0.3048)
			(end -0.67945 0.3048)
			(stroke
				(width 0.1)
				(type default)
			)
			(layer "B.Fab")
		)
		(fp_line
			(start -0.67945 0.3048)
			(end -0.120396 0.3048)
			(stroke
				(width 0.1)
				(type default)
			)
			(layer "B.Fab")
		)
		(fp_line
			(start -0.12065 -0.3048)
			(end -0.67945 -0.3048)
			(stroke
				(width 0.1)
				(type default)
			)
			(layer "B.Fab")
		)
		(fp_line
			(start -0.12065 -0.2794)
			(end -0.12065 -0.3048)
			(stroke
				(width 0.1)
				(type default)
			)
			(layer "B.Fab")
		)
		(fp_line
			(start -0.120396 0.2794)
			(end 0.12065 0.2794)
			(stroke
				(width 0.1)
				(type default)
			)
			(layer "B.Fab")
		)
		(fp_line
			(start -0.120396 0.3048)
			(end -0.120396 0.2794)
			(stroke
				(width 0.1)
				(type default)
			)
			(layer "B.Fab")
		)
		(fp_line
			(start 0.12065 -0.305054)
			(end 0.12065 -0.2794)
			(stroke
				(width 0.1)
				(type default)
			)
			(layer "B.Fab")
		)
		(fp_line
			(start 0.12065 -0.2794)
			(end -0.12065 -0.2794)
			(stroke
				(width 0.1)
				(type default)
			)
			(layer "B.Fab")
		)
		(fp_line
			(start 0.12065 0.2794)
			(end 0.12065 0.3048)
			(stroke
				(width 0.1)
				(type default)
			)
			(layer "B.Fab")
		)
		(fp_line
			(start 0.12065 0.3048)
			(end 0.67945 0.3048)
			(stroke
				(width 0.1)
				(type default)
			)
			(layer "B.Fab")
		)
		(fp_line
			(start 0.67945 -0.305054)
			(end 0.12065 -0.305054)
			(stroke
				(width 0.1)
				(type default)
			)
			(layer "B.Fab")
		)
		(fp_line
			(start 0.67945 0.3048)
			(end 0.67945 -0.305054)
			(stroke
				(width 0.1)
				(type default)
			)
			(layer "B.Fab")
		)
		(pad "1" smd circle
			(at 0.40005 0 180)
			(size 0 0)
			(layers "B.Cu" "B.Mask" "B.Paste")
			(net "M_J_CPU0_ALERT_N")
		)
		(pad "2" smd circle
			(at -0.40005 0 180)
			(size 0 0)
			(layers "B.Cu" "B.Mask" "B.Paste")
			(net "M_J_CPU0_ALERT_R_N")
		)
	)
	(footprint ""
		(layer "B.Cu")
		(at 115.686078 -26.025856 90)
		(property "Reference" "C6116"
			(at 0 0 90)
			(layer "B.SilkS")
			(hide yes)
			(effects
				(font
					(size 1.27 1.27)
				)
				(justify mirror)
			)
		)
		(property "Value" ""
			(at 0 0 90)
			(layer "B.Fab")
			(effects
				(font
					(size 1.27 1.27)
				)
				(justify mirror)
			)
		)
		(duplicate_pad_numbers_are_jumpers no)
		(fp_line
			(start 0.7874 -0.4064)
			(end -0.7874 -0.4064)
			(stroke
				(width 0.1524)
				(type default)
			)
			(layer "B.SilkS")
		)
		(fp_line
			(start -0.7874 -0.4064)
			(end -0.7874 0.4064)
			(stroke
				(width 0.1524)
				(type default)
			)
			(layer "B.SilkS")
		)
		(fp_line
			(start 0.7874 0.4064)
			(end 0.7874 -0.4064)
			(stroke
				(width 0.1524)
				(type default)
			)
			(layer "B.SilkS")
		)
		(fp_line
			(start -0.7874 0.4064)
			(end 0.7874 0.4064)
			(stroke
				(width 0.1524)
				(type default)
			)
			(layer "B.SilkS")
		)
		(fp_line
			(start 0.67945 -0.305054)
			(end 0.12065 -0.305054)
			(stroke
				(width 0.1)
				(type default)
			)
			(layer "B.Fab")
		)
		(fp_line
			(start 0.12065 -0.305054)
			(end 0.12065 -0.2794)
			(stroke
				(width 0.1)
				(type default)
			)
			(layer "B.Fab")
		)
		(fp_line
			(start -0.12065 -0.3048)
			(end -0.67945 -0.3048)
			(stroke
				(width 0.1)
				(type default)
			)
			(layer "B.Fab")
		)
		(fp_line
			(start -0.67945 -0.3048)
			(end -0.67945 0.3048)
			(stroke
				(width 0.1)
				(type default)
			)
			(layer "B.Fab")
		)
		(fp_line
			(start 0.12065 -0.2794)
			(end -0.12065 -0.2794)
			(stroke
				(width 0.1)
				(type default)
			)
			(layer "B.Fab")
		)
		(fp_line
			(start -0.12065 -0.2794)
			(end -0.12065 -0.3048)
			(stroke
				(width 0.1)
				(type default)
			)
			(layer "B.Fab")
		)
		(fp_line
			(start 0.12065 0.2794)
			(end 0.12065 0.3048)
			(stroke
				(width 0.1)
				(type default)
			)
			(layer "B.Fab")
		)
		(fp_line
			(start -0.120396 0.2794)
			(end 0.12065 0.2794)
			(stroke
				(width 0.1)
				(type default)
			)
			(layer "B.Fab")
		)
		(fp_line
			(start 0.67945 0.3048)
			(end 0.67945 -0.305054)
			(stroke
				(width 0.1)
				(type default)
			)
			(layer "B.Fab")
		)
		(fp_line
			(start 0.12065 0.3048)
			(end 0.67945 0.3048)
			(stroke
				(width 0.1)
				(type default)
			)
			(layer "B.Fab")
		)
		(fp_line
			(start -0.120396 0.3048)
			(end -0.120396 0.2794)
			(stroke
				(width 0.1)
				(type default)
			)
			(layer "B.Fab")
		)
		(fp_line
			(start -0.67945 0.3048)
			(end -0.120396 0.3048)
			(stroke
				(width 0.1)
				(type default)
			)
			(layer "B.Fab")
		)
		(pad "1" smd circle
			(at 0.40005 0 270)
			(size 0 0)
			(layers "B.Cu" "B.Mask" "B.Paste")
			(net "P1V2_CPU0_USB2_DVDD12")
		)
		(pad "2" smd circle
			(at -0.40005 0 270)
			(size 0 0)
			(layers "B.Cu" "B.Mask" "B.Paste")
			(net "GND")
		)
	)
)
